# T6G (Grand Teton) — schematic netlist excerpt (pin names and nets, part order shuffled) for the footprints in the layout excerpt that follows; sources: Cadence DE-HDL packaged netlist, KiCad conversion of 04192023_DAF0TMB3IC0_F0TG_MB_C_brd_V02_OCP.brd

R3490  Q_RES  1K 1% CHIP  pkg 0402LF  page 129 : A = P3V3_AUX ; B = GPU_FPGA_EROT_RECOV_N
R1484  Q_RES  1K 1% EMPTY  pkg 0201LF  page 309 : A = P1V8_CPU0_RT_1D ; B = JTAG_TDO_RT_CPU0_P3
C1977  Q_CAP  0.1UF 25V 10% X7R  pkg 0402  page 128 : A = P3V3_AUX ; B = GND

(kicad_pcb
	(version 20260206)
	(generator "pcbnew")
	(generator_version "10.0")
	(general
		(thickness 1.6)
		(legacy_teardrops no)
	)
	(paper "A4")
	(title_block
		(title "04192023_DAF0TMB3IC0_F0TG_MB_C_brd_V02_OCP.brd")
		(comment 1 "Grand Teton / footprints 1565-1567 of 8354")
	)
	(layers
		(0 "F.Cu" signal "TOP")
		(4 "In1.Cu" signal "GND")
		(6 "In2.Cu" signal "IN1")
		(8 "In3.Cu" signal "GND1")
		(10 "In4.Cu" signal "IN2")
		(12 "In5.Cu" signal "GND2")
		(14 "In6.Cu" signal "IN3")
		(16 "In7.Cu" signal "GND3")
		(18 "In8.Cu" signal "VCC")
		(20 "In9.Cu" signal "VCC1")
		(22 "In10.Cu" signal "GND4")
		(24 "In11.Cu" signal "IN4")
		(26 "In12.Cu" signal "GND5")
		(28 "In13.Cu" signal "IN5")
		(30 "In14.Cu" signal "GND6")
		(32 "In15.Cu" signal "IN6")
		(34 "In16.Cu" signal "GND7")
		(2 "B.Cu" signal "BOTTOM")
		(9 "F.Adhes" user "F.Adhesive")
		(11 "B.Adhes" user "B.Adhesive")
		(13 "F.Paste" user "Package Geometry/Pastemask Top")
		(15 "B.Paste" user "Package Geometry/Pastemask Bottom")
		(5 "F.SilkS" user "Ref Des/Silkscreen Top")
		(7 "B.SilkS" user "Ref Des/Silkscreen Bottom")
		(1 "F.Mask" user "Board Geometry/Soldermask Top")
		(3 "B.Mask" user "Board Geometry/Soldermask Bottom")
		(17 "Dwgs.User" user "User.Drawings")
		(19 "Cmts.User" user "User.Comments")
		(21 "Eco1.User" user "User.Eco1")
		(23 "Eco2.User" user "User.Eco2")
		(25 "Edge.Cuts" user "Board Geometry/Outline")
		(27 "Margin" user)
		(31 "F.CrtYd" user "Package Geometry/Place Bound Top")
		(29 "B.CrtYd" user "Package Geometry/Place Bound Bottom")
		(35 "F.Fab" user "Ref Des/Assembly Top")
		(33 "B.Fab" user "Ref Des/Assembly Bottom")
	)
	(footprint ""
		(layer "F.Cu")
		(at 42.545 -436.118 -90)
		(property "Reference" "C1977"
			(at 0 0 270)
			(layer "F.SilkS")
			(hide yes)
			(effects
				(font
					(size 1.27 1.27)
				)
			)
		)
		(property "Value" ""
			(at 0 0 270)
			(layer "F.Fab")
			(effects
				(font
					(size 1.27 1.27)
				)
			)
		)
		(duplicate_pad_numbers_are_jumpers no)
		(fp_line
			(start -0.7874 0.4064)
			(end -0.7874 -0.4064)
			(stroke
				(width 0.1524)
				(type default)
			)
			(layer "F.SilkS")
		)
		(fp_line
			(start 0.7874 0.4064)
			(end -0.7874 0.4064)
			(stroke
				(width 0.1524)
				(type default)
			)
			(layer "F.SilkS")
		)
		(fp_line
			(start -0.7874 -0.4064)
			(end 0.7874 -0.4064)
			(stroke
				(width 0.1524)
				(type default)
			)
			(layer "F.SilkS")
		)
		(fp_line
			(start 0.7874 -0.4064)
			(end 0.7874 0.4064)
			(stroke
				(width 0.1524)
				(type default)
			)
			(layer "F.SilkS")
		)
		(fp_line
			(start -0.67945 0.3048)
			(end -0.67945 -0.305054)
			(stroke
				(width 0.1)
				(type default)
			)
			(layer "F.Fab")
		)
		(fp_line
			(start -0.12065 0.3048)
			(end -0.67945 0.3048)
			(stroke
				(width 0.1)
				(type default)
			)
			(layer "F.Fab")
		)
		(fp_line
			(start 0.120396 0.3048)
			(end 0.120396 0.2794)
			(stroke
				(width 0.1)
				(type default)
			)
			(layer "F.Fab")
		)
		(fp_line
			(start 0.67945 0.3048)
			(end 0.120396 0.3048)
			(stroke
				(width 0.1)
				(type default)
			)
			(layer "F.Fab")
		)
		(fp_line
			(start -0.12065 0.2794)
			(end -0.12065 0.3048)
			(stroke
				(width 0.1)
				(type default)
			)
			(layer "F.Fab")
		)
		(fp_line
			(start 0.120396 0.2794)
			(end -0.12065 0.2794)
			(stroke
				(width 0.1)
				(type default)
			)
			(layer "F.Fab")
		)
		(fp_line
			(start -0.12065 -0.2794)
			(end 0.12065 -0.2794)
			(stroke
				(width 0.1)
				(type default)
			)
			(layer "F.Fab")
		)
		(fp_line
			(start 0.12065 -0.2794)
			(end 0.12065 -0.3048)
			(stroke
				(width 0.1)
				(type default)
			)
			(layer "F.Fab")
		)
		(fp_line
			(start 0.12065 -0.3048)
			(end 0.67945 -0.3048)
			(stroke
				(width 0.1)
				(type default)
			)
			(layer "F.Fab")
		)
		(fp_line
			(start 0.67945 -0.3048)
			(end 0.67945 0.3048)
			(stroke
				(width 0.1)
				(type default)
			)
			(layer "F.Fab")
		)
		(fp_line
			(start -0.67945 -0.305054)
			(end -0.12065 -0.305054)
			(stroke
				(width 0.1)
				(type default)
			)
			(layer "F.Fab")
		)
		(fp_line
			(start -0.12065 -0.305054)
			(end -0.12065 -0.2794)
			(stroke
				(width 0.1)
				(type default)
			)
			(layer "F.Fab")
		)
		(pad "1" smd circle
			(at -0.40005 0 270)
			(size 0 0)
			(layers "F.Cu" "F.Mask" "F.Paste")
			(net "P3V3_AUX")
		)
		(pad "2" smd circle
			(at 0.40005 0 270)
			(size 0 0)
			(layers "F.Cu" "F.Mask" "F.Paste")
			(net "GND")
		)
	)
	(footprint ""
		(layer "F.Cu")
		(at 120.396 -440.309 180)
		(property "Reference" "R3490"
			(at 0 0 180)
			(layer "F.SilkS")
			(hide yes)
			(effects
				(font
					(size 1.27 1.27)
				)
			)
		)
		(property "Value" ""
			(at 0 0 180)
			(layer "F.Fab")
			(effects
				(font
					(size 1.27 1.27)
				)
			)
		)
		(duplicate_pad_numbers_are_jumpers no)
		(fp_line
			(start 0.7874 0.4064)
			(end -0.7874 0.4064)
			(stroke
				(width 0.1524)
				(type default)
			)
			(layer "F.SilkS")
		)
		(fp_line
			(start 0.7874 -0.4064)
			(end 0.7874 0.4064)
			(stroke
				(width 0.1524)
				(type default)
			)
			(layer "F.SilkS")
		)
		(fp_line
			(start -0.7874 0.4064)
			(end -0.7874 -0.4064)
			(stroke
				(width 0.1524)
				(type default)
			)
			(layer "F.SilkS")
		)
		(fp_line
			(start -0.7874 -0.4064)
			(end 0.7874 -0.4064)
			(stroke
				(width 0.1524)
				(type default)
			)
			(layer "F.SilkS")
		)
		(fp_line
			(start 0.67945 0.3048)
			(end 0.120396 0.3048)
			(stroke
				(width 0.1)
				(type default)
			)
			(layer "F.Fab")
		)
		(fp_line
			(start 0.67945 -0.3048)
			(end 0.67945 0.3048)
			(stroke
				(width 0.1)
				(type default)
			)
			(layer "F.Fab")
		)
		(fp_line
			(start 0.12065 -0.2794)
			(end 0.12065 -0.3048)
			(stroke
				(width 0.1)
				(type default)
			)
			(layer "F.Fab")
		)
		(fp_line
			(start 0.12065 -0.3048)
			(end 0.67945 -0.3048)
			(stroke
				(width 0.1)
				(type default)
			)
			(layer "F.Fab")
		)
		(fp_line
			(start 0.120396 0.3048)
			(end 0.120396 0.2794)
			(stroke
				(width 0.1)
				(type default)
			)
			(layer "F.Fab")
		)
		(fp_line
			(start 0.120396 0.2794)
			(end -0.12065 0.2794)
			(stroke
				(width 0.1)
				(type default)
			)
			(layer "F.Fab")
		)
		(fp_line
			(start -0.12065 0.3048)
			(end -0.67945 0.3048)
			(stroke
				(width 0.1)
				(type default)
			)
			(layer "F.Fab")
		)
		(fp_line
			(start -0.12065 0.2794)
			(end -0.12065 0.3048)
			(stroke
				(width 0.1)
				(type default)
			)
			(layer "F.Fab")
		)
		(fp_line
			(start -0.12065 -0.2794)
			(end 0.12065 -0.2794)
			(stroke
				(width 0.1)
				(type default)
			)
			(layer "F.Fab")
		)
		(fp_line
			(start -0.12065 -0.305054)
			(end -0.12065 -0.2794)
			(stroke
				(width 0.1)
				(type default)
			)
			(layer "F.Fab")
		)
		(fp_line
			(start -0.67945 0.3048)
			(end -0.67945 -0.305054)
			(stroke
				(width 0.1)
				(type default)
			)
			(layer "F.Fab")
		)
		(fp_line
			(start -0.67945 -0.305054)
			(end -0.12065 -0.305054)
			(stroke
				(width 0.1)
				(type default)
			)
			(layer "F.Fab")
		)
		(pad "1" smd circle
			(at -0.40005 0 180)
			(size 0 0)
			(layers "F.Cu" "F.Mask" "F.Paste")
			(net "P3V3_AUX")
		)
		(pad "2" smd circle
			(at 0.40005 0 180)
			(size 0 0)
			(layers "F.Cu" "F.Mask" "F.Paste")
			(net "GPU_FPGA_EROT_RECOV_N")
		)
	)
	(footprint ""
		(layer "F.Cu")
		(at 426.1612 -421.64 90)
		(property "Reference" "R1484"
			(at 0 0 90)
			(layer "F.SilkS")
			(hide yes)
			(effects
				(font
					(size 1.27 1.27)
				)
			)
		)
		(property "Value" ""
			(at 0 0 90)
			(layer "F.Fab")
			(effects
				(font
					(size 1.27 1.27)
				)
			)
		)
		(duplicate_pad_numbers_are_jumpers no)
		(fp_line
			(start 0.32512 -0.175006)
			(end 0.32512 0.175006)
			(stroke
				(width 0.1)
				(type default)
			)
			(layer "F.Fab")
		)
		(fp_line
			(start -0.32512 -0.175006)
			(end 0.32512 -0.175006)
			(stroke
				(width 0.1)
				(type default)
			)
			(layer "F.Fab")
		)
		(fp_line
			(start 0.32512 0.175006)
			(end -0.32512 0.175006)
			(stroke
				(width 0.1)
				(type default)
			)
			(layer "F.Fab")
		)
		(fp_line
			(start -0.32512 0.175006)
			(end -0.32512 -0.175006)
			(stroke
				(width 0.1)
				(type default)
			)
			(layer "F.Fab")
		)
		(pad "1" smd rect
			(at -0.2667 0 90)
			(size 0.3048 0.381)
			(layers "F.Cu" "F.Mask" "F.Paste")
			(net "P1V8_CPU0_RT_1D")
		)
		(pad "2" smd rect
			(at 0.2667 0 270)
			(size 0.3048 0.381)
			(layers "F.Cu" "F.Mask" "F.Paste")
			(net "JTAG_TDO_RT_CPU0_P3")
		)
	)
)
